#ISCELL
  mstr_misc dns *
  *
#ISCELL
  pure_quanta quanta_title_block_c *
  *
#ISCELL
  standard offpage *
  page278_i1
#ISCELL
  standard offpage *
  page278_i10
#ISCELL
  logical_power universal_gnd *
  page278_i100
#ISCELL
  standard offpage *
  page278_i101
#ISCELL
  logical_power vcc15 *
  page278_i102
#CELL
  pure_quanta q_res *
  page278_i103
#CELL
  pure_quanta q_res *
  page278_i104
#CELL
  pure_quanta q_res *
  page278_i105
#CELL
  pure_quanta q_cap *
  page278_i106
#ISCELL
  logical_power universal_gnd *
  page278_i107
#CELL
  pure_quanta q_res *
  page278_i108
#ISCELL
  logical_power vcc15 *
  page278_i109
#ISCELL
  standard offpage *
  page278_i11
#CELL
  pure_quanta q_res *
  page278_i110
#CELL
  pure_quanta q_cap *
  page278_i111
#ISCELL
  standard offpage *
  page278_i12
#ISCELL
  standard offpage *
  page278_i13
#CELL
  pure_quanta q_res *
  page278_i14
#CELL
  pure_quanta q_res *
  page278_i15
#ISCELL
  logical_power vcc15 *
  page278_i16
#ISCELL
  standard offpage *
  page278_i17
#ISCELL
  standard offpage *
  page278_i18
#ISCELL
  logical_power universal_gnd *
  page278_i19
#ISCELL
  standard offpage *
  page278_i2
#CELL
  pure_quanta q_res *
  page278_i21
#CELL
  pure_quanta q_res *
  page278_i22
#CELL
  pure_quanta q_res *
  page278_i23
#ISCELL
  logical_power vcc15 *
  page278_i24
#ISCELL
  logical_power vcc15 *
  page278_i25
#CELL
  pure_quanta q_res *
  page278_i26
#ISCELL
  logical_power universal_gnd *
  page278_i27
#CELL
  pure_quanta q_cap *
  page278_i28
#CELL
  pure_quanta q_res *
  page278_i29
#ISCELL
  standard offpage *
  page278_i3
#CELL
  pure_quanta q_res *
  page278_i30
#CELL
  pure_quanta q_res *
  page278_i31
#CELL
  pure_quanta q_cap *
  page278_i32
#CELL
  pure_quanta q_cap *
  page278_i33
#ISCELL
  logical_power universal_gnd *
  page278_i34
#CELL
  pure_quanta q_res *
  page278_i35
#CELL
  pure_quanta q_cap *
  page278_i36
#ISCELL
  logical_power universal_gnd *
  page278_i37
#CELL
  pure_quanta isl69260irazt *
  page278_i38
#ISCELL
  logical_power universal_gnd *
  page278_i39
#ISCELL
  standard offpage *
  page278_i4
#ISCELL
  logical_power universal_gnd *
  page278_i40
#CELL
  pure_quanta q_res *
  page278_i41
#ISCELL
  logical_power vcc15 *
  page278_i42
#ISCELL
  logical_power universal_gnd *
  page278_i43
#CELL
  pure_quanta q_short *
  page278_i44
#CELL
  pure_quanta q_res *
  page278_i45
#CELL
  pure_quanta q_res *
  page278_i46
#ISCELL
  logical_power vcc15 *
  page278_i47
#ISCELL
  logical_power universal_gnd *
  page278_i48
#CELL
  pure_quanta q_res *
  page278_i49
#ISCELL
  standard offpage *
  page278_i5
#CELL
  pure_quanta q_res *
  page278_i50
#CELL
  pure_quanta q_cap *
  page278_i51
#CELL
  pure_quanta q_res *
  page278_i52
#CELL
  pure_quanta q_cap *
  page278_i53
#CELL
  pure_quanta q_short *
  page278_i54
#CELL
  pure_quanta q_res *
  page278_i55
#ISCELL
  logical_power vcc15 *
  page278_i56
#CELL
  pure_quanta q_res *
  page278_i57
#CELL
  pure_quanta q_res *
  page278_i58
#CELL
  pure_quanta q_res *
  page278_i59
#ISCELL
  standard offpage *
  page278_i6
#CELL
  pure_quanta q_res *
  page278_i60
#CELL
  pure_quanta q_res *
  page278_i61
#CELL
  pure_quanta q_res *
  page278_i62
#CELL
  pure_quanta q_cap *
  page278_i63
#ISCELL
  logical_power universal_gnd *
  page278_i64
#ISCELL
  logical_power universal_gnd *
  page278_i65
#CELL
  pure_quanta q_cap *
  page278_i66
#CELL
  pure_quanta q_res *
  page278_i67
#ISCELL
  logical_power universal_gnd *
  page278_i68
#CELL
  pure_quanta q_cap *
  page278_i69
#ISCELL
  standard offpage *
  page278_i7
#CELL
  pure_quanta q_res *
  page278_i70
#ISCELL
  logical_power universal_gnd *
  page278_i71
#ISCELL
  standard offpage *
  page278_i72
#CELL
  pure_quanta q_res *
  page278_i73
#ISCELL
  logical_power universal_gnd *
  page278_i74
#CELL
  pure_quanta q_res *
  page278_i75
#ISCELL
  standard offpage *
  page278_i76
#ISCELL
  standard offpage *
  page278_i77
#CELL
  pure_quanta q_res *
  page278_i78
#CELL
  pure_quanta q_res *
  page278_i79
#ISCELL
  standard offpage *
  page278_i8
#CELL
  pure_quanta q_res *
  page278_i80
#CELL
  pure_quanta q_res *
  page278_i81
#ISCELL
  standard offpage *
  page278_i82
#ISCELL
  standard offpage *
  page278_i83
#ISCELL
  logical_power universal_gnd *
  page278_i84
#ISCELL
  logical_power vcc15 *
  page278_i85
#ISCELL
  logical_power universal_gnd *
  page278_i86
#ISCELL
  logical_power universal_gnd *
  page278_i87
#ISCELL
  logical_power universal_gnd *
  page278_i88
#CELL
  pure_quanta q_res *
  page278_i89
#ISCELL
  standard offpage *
  page278_i9
#ISCELL
  standard offpage *
  page278_i90
#ISCELL
  standard offpage *
  page278_i91
#CELL
  pure_quanta q_cap *
  page278_i92
#CELL
  pure_quanta q_cap *
  page278_i93
#ISCELL
  standard offpage *
  page278_i94
#ISCELL
  standard offpage *
  page278_i95
#CELL
  pure_quanta q_cap *
  page278_i96
#CELL
  pure_quanta q_cap *
  page278_i97
#ISCELL
  logical_power universal_gnd *
  page278_i98
#ISCELL
  logical_power universal_gnd *
  page278_i99
